# S9S_MB_2U (Grand Teton) — schematic netlist excerpt (pin names and nets, part order shuffled) for the footprints in the layout excerpt that follows; sources: Cadence DE-HDL packaged netlist, KiCad conversion of 03242023_DA0F0TMBIJ0_F0T_Motherboard_J_brd_V01_OCP.brd

PR304  Q_RES  0 5% EMPTY  pkg 0402LF  page 284 : A = P12V_AUX ; B = PVCCIN_CPU1_CSPIN
R4087  Q_RES  33.2 1% CHIP  pkg 0402LF  page 240 : A = FM_JTAG_BMC_MUX_SEL_FROM_BMC_R ; B = FM_JTAG_BMC_MUX_SEL_FROM_BMC_R2
C493  Q_CAP  47UF 4V 20% X6S  pkg C0805  page 75 : A = PVCCFA_EHV_FIVRA_CPU0 ; B = GND

(kicad_pcb
	(version 20260206)
	(generator "pcbnew")
	(generator_version "10.0")
	(general
		(thickness 1.6)
		(legacy_teardrops no)
	)
	(paper "A4")
	(title_block
		(title "03242023_DA0F0TMBIJ0_F0T_Motherboard_J_brd_V01_OCP.brd")
		(comment 1 "Grand Teton / footprints 4987-4989 of 6105")
	)
	(layers
		(0 "F.Cu" signal "TOP")
		(4 "In1.Cu" signal "GND")
		(6 "In2.Cu" signal "IN1")
		(8 "In3.Cu" signal "GND1")
		(10 "In4.Cu" signal "IN2")
		(12 "In5.Cu" signal "GND2")
		(14 "In6.Cu" signal "IN3")
		(16 "In7.Cu" signal "GND3")
		(18 "In8.Cu" signal "VCC")
		(20 "In9.Cu" signal "VCC1")
		(22 "In10.Cu" signal "GND4")
		(24 "In11.Cu" signal "IN4")
		(26 "In12.Cu" signal "GND5")
		(28 "In13.Cu" signal "IN5")
		(30 "In14.Cu" signal "GND6")
		(32 "In15.Cu" signal "IN6")
		(34 "In16.Cu" signal "GND7")
		(2 "B.Cu" signal "BOTTOM")
		(9 "F.Adhes" user "F.Adhesive")
		(11 "B.Adhes" user "B.Adhesive")
		(13 "F.Paste" user "Package Geometry/Pastemask Top")
		(15 "B.Paste" user "Package Geometry/Pastemask Bottom")
		(5 "F.SilkS" user "Ref Des/Silkscreen Top")
		(7 "B.SilkS" user "Ref Des/Silkscreen Bottom")
		(1 "F.Mask" user "Board Geometry/Soldermask Top")
		(3 "B.Mask" user "Board Geometry/Soldermask Bottom")
		(17 "Dwgs.User" user "User.Drawings")
		(19 "Cmts.User" user "User.Comments")
		(21 "Eco1.User" user "User.Eco1")
		(23 "Eco2.User" user "User.Eco2")
		(25 "Edge.Cuts" user "Board Geometry/Outline")
		(27 "Margin" user)
		(31 "F.CrtYd" user "Package Geometry/Place Bound Top")
		(29 "B.CrtYd" user "Package Geometry/Place Bound Bottom")
		(35 "F.Fab" user "Ref Des/Assembly Top")
		(33 "B.Fab" user "Ref Des/Assembly Bottom")
	)
	(footprint ""
		(layer "B.Cu")
		(at 114.374676 -360.418126 -90)
		(property "Reference" "PR304"
			(at 0 0 90)
			(layer "B.SilkS")
			(hide yes)
			(effects
				(font
					(size 1.27 1.27)
				)
				(justify mirror)
			)
		)
		(property "Value" ""
			(at 0 0 90)
			(layer "B.Fab")
			(effects
				(font
					(size 1.27 1.27)
				)
				(justify mirror)
			)
		)
		(duplicate_pad_numbers_are_jumpers no)
		(fp_line
			(start -0.7874 0.4064)
			(end 0.7874 0.4064)
			(stroke
				(width 0.1524)
				(type default)
			)
			(layer "B.SilkS")
		)
		(fp_line
			(start 0.7874 0.4064)
			(end 0.7874 -0.4064)
			(stroke
				(width 0.1524)
				(type default)
			)
			(layer "B.SilkS")
		)
		(fp_line
			(start -0.7874 -0.4064)
			(end -0.7874 0.4064)
			(stroke
				(width 0.1524)
				(type default)
			)
			(layer "B.SilkS")
		)
		(fp_line
			(start 0.7874 -0.4064)
			(end -0.7874 -0.4064)
			(stroke
				(width 0.1524)
				(type default)
			)
			(layer "B.SilkS")
		)
		(fp_line
			(start -0.67945 0.3048)
			(end -0.120396 0.3048)
			(stroke
				(width 0.1)
				(type default)
			)
			(layer "B.Fab")
		)
		(fp_line
			(start -0.120396 0.3048)
			(end -0.120396 0.2794)
			(stroke
				(width 0.1)
				(type default)
			)
			(layer "B.Fab")
		)
		(fp_line
			(start 0.12065 0.3048)
			(end 0.67945 0.3048)
			(stroke
				(width 0.1)
				(type default)
			)
			(layer "B.Fab")
		)
		(fp_line
			(start 0.67945 0.3048)
			(end 0.67945 -0.305054)
			(stroke
				(width 0.1)
				(type default)
			)
			(layer "B.Fab")
		)
		(fp_line
			(start -0.120396 0.2794)
			(end 0.12065 0.2794)
			(stroke
				(width 0.1)
				(type default)
			)
			(layer "B.Fab")
		)
		(fp_line
			(start 0.12065 0.2794)
			(end 0.12065 0.3048)
			(stroke
				(width 0.1)
				(type default)
			)
			(layer "B.Fab")
		)
		(fp_line
			(start -0.12065 -0.2794)
			(end -0.12065 -0.3048)
			(stroke
				(width 0.1)
				(type default)
			)
			(layer "B.Fab")
		)
		(fp_line
			(start 0.12065 -0.2794)
			(end -0.12065 -0.2794)
			(stroke
				(width 0.1)
				(type default)
			)
			(layer "B.Fab")
		)
		(fp_line
			(start -0.67945 -0.3048)
			(end -0.67945 0.3048)
			(stroke
				(width 0.1)
				(type default)
			)
			(layer "B.Fab")
		)
		(fp_line
			(start -0.12065 -0.3048)
			(end -0.67945 -0.3048)
			(stroke
				(width 0.1)
				(type default)
			)
			(layer "B.Fab")
		)
		(fp_line
			(start 0.12065 -0.305054)
			(end 0.12065 -0.2794)
			(stroke
				(width 0.1)
				(type default)
			)
			(layer "B.Fab")
		)
		(fp_line
			(start 0.67945 -0.305054)
			(end 0.12065 -0.305054)
			(stroke
				(width 0.1)
				(type default)
			)
			(layer "B.Fab")
		)
		(pad "1" smd circle
			(at 0.40005 0 90)
			(size 0 0)
			(layers "B.Cu" "B.Mask" "B.Paste")
			(net "P12V_AUX")
		)
		(pad "2" smd circle
			(at -0.40005 0 90)
			(size 0 0)
			(layers "B.Cu" "B.Mask" "B.Paste")
			(net "PVCCIN_CPU1_CSPIN")
		)
	)
	(footprint ""
		(layer "B.Cu")
		(at 146.3548 -13.772388 90)
		(property "Reference" "R4087"
			(at 0 0 90)
			(layer "B.SilkS")
			(hide yes)
			(effects
				(font
					(size 1.27 1.27)
				)
				(justify mirror)
			)
		)
		(property "Value" ""
			(at 0 0 90)
			(layer "B.Fab")
			(effects
				(font
					(size 1.27 1.27)
				)
				(justify mirror)
			)
		)
		(duplicate_pad_numbers_are_jumpers no)
		(fp_line
			(start 0.7874 -0.4064)
			(end -0.7874 -0.4064)
			(stroke
				(width 0.1524)
				(type default)
			)
			(layer "B.SilkS")
		)
		(fp_line
			(start -0.7874 -0.4064)
			(end -0.7874 0.4064)
			(stroke
				(width 0.1524)
				(type default)
			)
			(layer "B.SilkS")
		)
		(fp_line
			(start 0.7874 0.4064)
			(end 0.7874 -0.4064)
			(stroke
				(width 0.1524)
				(type default)
			)
			(layer "B.SilkS")
		)
		(fp_line
			(start -0.7874 0.4064)
			(end 0.7874 0.4064)
			(stroke
				(width 0.1524)
				(type default)
			)
			(layer "B.SilkS")
		)
		(fp_line
			(start 0.67945 -0.305054)
			(end 0.12065 -0.305054)
			(stroke
				(width 0.1)
				(type default)
			)
			(layer "B.Fab")
		)
		(fp_line
			(start 0.12065 -0.305054)
			(end 0.12065 -0.2794)
			(stroke
				(width 0.1)
				(type default)
			)
			(layer "B.Fab")
		)
		(fp_line
			(start -0.12065 -0.3048)
			(end -0.67945 -0.3048)
			(stroke
				(width 0.1)
				(type default)
			)
			(layer "B.Fab")
		)
		(fp_line
			(start -0.67945 -0.3048)
			(end -0.67945 0.3048)
			(stroke
				(width 0.1)
				(type default)
			)
			(layer "B.Fab")
		)
		(fp_line
			(start 0.12065 -0.2794)
			(end -0.12065 -0.2794)
			(stroke
				(width 0.1)
				(type default)
			)
			(layer "B.Fab")
		)
		(fp_line
			(start -0.12065 -0.2794)
			(end -0.12065 -0.3048)
			(stroke
				(width 0.1)
				(type default)
			)
			(layer "B.Fab")
		)
		(fp_line
			(start 0.12065 0.2794)
			(end 0.12065 0.3048)
			(stroke
				(width 0.1)
				(type default)
			)
			(layer "B.Fab")
		)
		(fp_line
			(start -0.120396 0.2794)
			(end 0.12065 0.2794)
			(stroke
				(width 0.1)
				(type default)
			)
			(layer "B.Fab")
		)
		(fp_line
			(start 0.67945 0.3048)
			(end 0.67945 -0.305054)
			(stroke
				(width 0.1)
				(type default)
			)
			(layer "B.Fab")
		)
		(fp_line
			(start 0.12065 0.3048)
			(end 0.67945 0.3048)
			(stroke
				(width 0.1)
				(type default)
			)
			(layer "B.Fab")
		)
		(fp_line
			(start -0.120396 0.3048)
			(end -0.120396 0.2794)
			(stroke
				(width 0.1)
				(type default)
			)
			(layer "B.Fab")
		)
		(fp_line
			(start -0.67945 0.3048)
			(end -0.120396 0.3048)
			(stroke
				(width 0.1)
				(type default)
			)
			(layer "B.Fab")
		)
		(pad "1" smd circle
			(at 0.40005 0 270)
			(size 0 0)
			(layers "B.Cu" "B.Mask" "B.Paste")
			(net "FM_JTAG_BMC_MUX_SEL_FROM_BMC_R")
		)
		(pad "2" smd circle
			(at -0.40005 0 270)
			(size 0 0)
			(layers "B.Cu" "B.Mask" "B.Paste")
			(net "FM_JTAG_BMC_MUX_SEL_FROM_BMC_R2")
		)
	)
	(footprint ""
		(layer "B.Cu")
		(at 366.120934 -259.531866 90)
		(property "Reference" "C493"
			(at 0 0 90)
			(layer "B.SilkS")
			(hide yes)
			(effects
				(font
					(size 1.27 1.27)
				)
				(justify mirror)
			)
		)
		(property "Value" ""
			(at 0 0 90)
			(layer "B.Fab")
			(effects
				(font
					(size 1.27 1.27)
				)
				(justify mirror)
			)
		)
		(duplicate_pad_numbers_are_jumpers no)
		(fp_line
			(start 1.524 -0.762)
			(end -1.524 -0.762)
			(stroke
				(width 0.1524)
				(type default)
			)
			(layer "B.SilkS")
		)
		(fp_line
			(start -1.524 -0.762)
			(end -1.524 0.762)
			(stroke
				(width 0.1524)
				(type default)
			)
			(layer "B.SilkS")
		)
		(fp_line
			(start 1.524 0.762)
			(end 1.524 -0.762)
			(stroke
				(width 0.1524)
				(type default)
			)
			(layer "B.SilkS")
		)
		(fp_line
			(start -1.524 0.762)
			(end 1.524 0.762)
			(stroke
				(width 0.1524)
				(type default)
			)
			(layer "B.SilkS")
		)
		(fp_line
			(start 1.1049 -0.724916)
			(end 1.1049 0.724916)
			(stroke
				(width 0.1)
				(type default)
			)
			(layer "B.Fab")
		)
		(fp_line
			(start -1.1049 -0.724916)
			(end 1.1049 -0.724916)
			(stroke
				(width 0.1)
				(type default)
			)
			(layer "B.Fab")
		)
		(fp_line
			(start 1.1049 0.724916)
			(end -1.1049 0.724916)
			(stroke
				(width 0.1)
				(type default)
			)
			(layer "B.Fab")
		)
		(fp_line
			(start -1.1049 0.724916)
			(end -1.1049 -0.724916)
			(stroke
				(width 0.1)
				(type default)
			)
			(layer "B.Fab")
		)
		(pad "1" smd rect
			(at 0.889 0 90)
			(size 1.016 1.27)
			(layers "B.Cu" "B.Mask" "B.Paste")
			(net "PVCCFA_EHV_FIVRA_CPU0")
		)
		(pad "2" smd rect
			(at -0.889 0 90)
			(size 1.016 1.27)
			(layers "B.Cu" "B.Mask" "B.Paste")
			(net "GND")
		)
	)
)
